# T6G (Grand Teton) — schematic parts with pin connectivity, parts 4355–4515 of 8303; source: Cadence DE-HDL packaged netlist (pstxprt.dat, pstxnet.dat, pstchip.dat)

PR3850  Q_RES  100 1% EMPTY  pkg 0402LF  page 141 : 1 = P12V_OCP_V3_2 ; 2 = P12V_OCP_AVIN_PD_2
PR3851  Q_RES  10K 1% CHIP  pkg 0402LF  page 141 : 1 = P12V_OCP_FLTB_2 ; 2 = P3V3_AUX
PR3852  Q_RES  71.5K 1% EMPTY  pkg 0402LF  page 141 : 1 = P12V_OCP_V3_2 ; 2 = P12V_OCP_OV_FB_2
PR3853  Q_RES  120K 1% CHIP  pkg 0402LF  page 141 : 1 = P12V_AUX ; 2 = P12V_OCP_OV_FB_2
PR3854  Q_RES  10K 1% CHIP  pkg 0402LF  page 141 : 1 = P12V_OCP_OV_FB_2 ; 2 = GND
PR3855  Q_RES  71.5K 1% CHIP  pkg 0402LF  page 141 : 1 = P3V3_OCP_MODE_2 ; 2 = GND
PR3856  Q_RES  1.33K 1% CHIP  pkg 0402LF  page 141 : 1 = GND ; 2 = P3V3_OCP_ILIMIT_2
PR3857  Q_RES  49.9 1% CHIP  pkg 0603LF  page 141 : 1 = P12V_AUX ; 2 = P12V_OCP_AVIN_PD_2
PR3910  Q_RES  0 5% CHIP  pkg 0402LF  page 263 : 1 = HSC_VDD_R_1 ; 2 = HSC_VDD
PR3911  Q_RES  0 5% CHIP  pkg 0402LF  page 263 : 1 = HSC_VDD_R_2 ; 2 = HSC_VDD
PR3912  Q_RES  120K 1% CHIP  pkg 0402LF  page 263 : 1 = AGND_HSC ; 2 = HSC_MODE_2
PR3914  Q_RES  2K 0.1% CHIP  pkg 0402LF  page 263 : 1 = HSC_CS_1 ; 2 = AGND_HSC
PR3915  Q_RES  2K 0.1% CHIP  pkg 0402LF  page 263 : 1 = HSC_CS_2 ; 2 = AGND_HSC
PR3916  Q_RES  0 5% CHIP  pkg 0402LF  page 263 : 1 = HSC_SCREF ; 2 = HSC_SCREF_1
PR3917  Q_RES  0 5% CHIP  pkg 0402LF  page 263 : 1 = HSC_SCREF ; 2 = HSC_SCREF_2
PR3918  Q_RES  2K 0.1% CHIP  pkg 0402LF  page 263 : 1 = HSC_IMON ; 2 = AGND_HSC
PR3919  Q_RES  0 5% CHIP  pkg 0402LF  page 263 : 1 = HSC_D_OC_1 ; 2 = HSC_D_OC_R
PR3920  Q_RES  0 5% CHIP  pkg 0402LF  page 263 : 1 = HSC_FLT_TYPE_1 ; 2 = HSC_FLT_TYPE
PR3921  Q_RES  0 5% CHIP  pkg 0402LF  page 263 : 1 = HSC_D_OC_2 ; 2 = HSC_D_OC_R
PR3922  Q_RES  0 5% CHIP  pkg 0402LF  page 263 : 1 = HSC_FLT_TYPE_2 ; 2 = HSC_FLT_TYPE
PR3926  Q_RES  75K 0.1% CHIP  pkg 0402LF  page 262 : 1 = P12V_PSU ; 2 = HSC_VSENSE
PR3927  Q_RES  4.99K 0.1% CHIP  pkg 0402LF  page 262 : 1 = HSC_VSENSE ; 2 = AGND_HSC
PR3928  Q_RES  0 5% CHIP  pkg 0402LF  page 262 : 1 = HSC_ON ; 2 = HSC_ON_R
PR3929  Q_RES  1K 1% EMPTY  pkg 0402LF  page 262 : 1 = HSC_ADDR ; 2 = HSC_VDD18
PR3930  Q_RES  0 5% CHIP  pkg 0402LF  page 262 : 1 = AGND_HSC ; 2 = HSC_ADDR
PR3931  Q_RES  75K 0.1% CHIP  pkg 0402LF  page 262 : 1 = P12V_AUX ; 2 = HSC_VOSEN
PR3932  Q_RES  4.99K 0.1% CHIP  pkg 0402LF  page 262 : 1 = HSC_VOSEN ; 2 = AGND_HSC
PR3935  Q_RES  10K 1% CHIP  pkg 0402LF  page 262 : 1 = HSC_VTEMP ; 2 = AGND_HSC
PR3937  Q_RES  120K 1% CHIP  pkg 0402LF  page 262 : 1 = HSC_MODE ; 2 = AGND_HSC
PR3944  Q_RES  46.4K 1% CHIP  pkg 0402LF  page 147 : 1 = P12V_E1S_ISET_0 ; 2 = GND
PR3945  Q_RES  71.5K 1% CHIP  pkg 0402LF  page 147 : 1 = P3V3_E1S_MODE_0 ; 2 = GND
PR3947  Q_RES  2.8K 1% CHIP  pkg 0402LF  page 147 : 1 = GND ; 2 = P3V3_E1S_ILIMIT_0
PR3949  Q_RES  56K 1% CHIP  pkg 0402LF  page 147 : 1 = P12V_E1S_IMON_0 ; 2 = GND
PR3950  Q_RES  100 1% EMPTY  pkg 0402LF  page 147 : 1 = P12V_E1S_0 ; 2 = P12V_E1S_AVIN_PD_0
PR3951  Q_RES  10K 1% CHIP  pkg 0402LF  page 147 : 1 = P12V_E1S_FLTB_0 ; 2 = P3V3_AUX
PR3952  Q_RES  71.5K 1% EMPTY  pkg 0402LF  page 147 : 1 = P12V_E1S_0 ; 2 = P12V_E1S_OV_FB_0
PR3953  Q_RES  120K 1% CHIP  pkg 0402LF  page 147 : 1 = P12V_AUX ; 2 = P12V_E1S_OV_FB_0
PR3954  Q_RES  10K 1% CHIP  pkg 0402LF  page 147 : 1 = P12V_E1S_OV_FB_0 ; 2 = GND
PR3957  Q_RES  49.9 1% CHIP  pkg 0603LF  page 147 : 1 = P12V_AUX ; 2 = P12V_E1S_AVIN_PD_0
PR3960  Q_RES  160K 1% CHIP  pkg 0402LF  page 146 : 1 = P12V_AUX ; 2 = P12V_E1S_UV_0
PR3961  Q_RES  6.8K 1% CHIP  pkg 0402LF  page 146 : 1 = P12V_E1S_UV_0 ; 2 = P12V_E1S_OV_0
PR3962  Q_RES  15K 1% CHIP  pkg 0402LF  page 146 : 1 = P12V_E1S_OV_0 ; 2 = GND
PR3963  Q_RES  25.5K 1% CHIP  pkg 0402LF  page 146 : 1 = P3V3_AUX ; 2 = P3V3_E1S_UV_0
PR3964  Q_RES  7.15K 1% CHIP  pkg 0402LF  page 146 : 1 = P3V3_E1S_UV_0 ; 2 = P3V3_E1S_OV_0
PR3965  Q_RES  15K 1% CHIP  pkg 0402LF  page 146 : 1 = P3V3_E1S_OV_0 ; 2 = GND
PR3966  Q_RES  10 1% CHIP  pkg 0402LF  page 146 : 1 = P12V_AUX ; 2 = P12V_E1S_VCC_0
PR3967  Q_RES  10 1% CHIP  pkg 0402LF  page 146 : 1 = P3V3_AUX ; 2 = P3V3_E1S_VCC_0
PR3968  Q_RES  9.31K 1% CHIP  pkg 0402LF  page 146 : 1 = P12V_E1S_CB_0 ; 2 = GND
PR3969  Q_RES  2.49K 1% CHIP  pkg 0402LF  page 146 : 1 = P3V3_E1S_CB_0 ; 2 = GND
PR3970  Q_RES  2.67K 1% CHIP  pkg 0402LF  page 146 : 1 = P12V_E1S_SENSE_0 ; 2 = GND
PR3971  Q_RES  9.76K 1% CHIP  pkg 0402LF  page 146 : 1 = P3V3_E1S_SENSE_0 ; 2 = GND
PR3980  Q_RES  0 5% CHIP  pkg 0402LF  page 264 : 1 = HSC_VDD_R_3 ; 2 = HSC_VDD
PR3981  Q_RES  0 5% CHIP  pkg 0402LF  page 264 : 1 = HSC_VDD_R_4 ; 2 = HSC_VDD
PR3982  Q_RES  120K 1% CHIP  pkg 0402LF  page 264 : 1 = AGND_HSC ; 2 = HSC_MODE_3
PR3984  Q_RES  120K 1% CHIP  pkg 0402LF  page 264 : 1 = AGND_HSC ; 2 = HSC_MODE_4
PR3986  Q_RES  2K 0.1% CHIP  pkg 0402LF  page 264 : 1 = HSC_CS_3 ; 2 = AGND_HSC
PR3987  Q_RES  2K 0.1% CHIP  pkg 0402LF  page 264 : 1 = HSC_CS_4 ; 2 = AGND_HSC
PR3988  Q_RES  0 5% CHIP  pkg 0402LF  page 264 : 1 = HSC_SCREF ; 2 = HSC_SCREF_3
PR3989  Q_RES  0 5% CHIP  pkg 0402LF  page 264 : 1 = HSC_SCREF ; 2 = HSC_SCREF_4
PR3990  Q_RES  2K 0.1% CHIP  pkg 0402LF  page 264 : 1 = HSC_IMON ; 2 = AGND_HSC
PR3991  Q_RES  2K 0.1% CHIP  pkg 0402LF  page 264 : 1 = HSC_IMON ; 2 = AGND_HSC
PR3992  Q_RES  0 5% CHIP  pkg 0402LF  page 264 : 1 = HSC_D_OC_3 ; 2 = HSC_D_OC_R
PR3993  Q_RES  0 5% CHIP  pkg 0402LF  page 264 : 1 = HSC_FLT_TYPE_3 ; 2 = HSC_FLT_TYPE
PR3994  Q_RES  0 5% CHIP  pkg 0402LF  page 264 : 1 = HSC_D_OC_4 ; 2 = HSC_D_OC_R
PR3995  Q_RES  0 5% CHIP  pkg 0402LF  page 264 : 1 = HSC_FLT_TYPE_4 ; 2 = HSC_FLT_TYPE
PR3999  Q_RES  24.3K 1% CHIP  pkg 0402LF  page 152 : 1 = P12V_SCM_ISET ; 2 = GND
PR4000  Q_RES  160K 1% CHIP  pkg 0402LF  page 152 : 1 = P12V_AUX ; 2 = P12V_SCM_UV
PR4001  Q_RES  6.8K 1% CHIP  pkg 0402LF  page 152 : 1 = P12V_SCM_UV ; 2 = P12V_SCM_OV
PR4002  Q_RES  15K 1% CHIP  pkg 0402LF  page 152 : 1 = P12V_SCM_OV ; 2 = GND
PR4003  Q_RES  10 1% CHIP  pkg 0402LF  page 152 : 1 = P12V_AUX ; 2 = P12V_SCM_VCC
PR4004  Q_RES  17.8K 1% CHIP  pkg 0402LF  page 152 : 1 = P12V_SCM_CB ; 2 = GND
PR4005  Q_RES  30.1K 1% CHIP  pkg 0402LF  page 152 : 1 = P12V_SCM_IMON ; 2 = GND
PR4006  Q_RES  100 1% EMPTY  pkg 0402LF  page 152 : 1 = P12V_SCM_R ; 2 = P12V_SCM_AVIN_PD
PR4007  Q_RES  10K 1% CHIP  pkg 0402LF  page 152 : 1 = P12V_SCM_FLTB_N ; 2 = P3V3_AUX
PR4008  Q_RES  1.33K 1% CHIP  pkg 0402LF  page 152 : 1 = P12V_SCM_SENSE ; 2 = GND
PR4009  Q_RES  71.5K 1% EMPTY  pkg 0402LF  page 152 : 1 = P12V_SCM_R ; 2 = P12V_SCM_OV_FB
PR4010  Q_RES  120K 1% CHIP  pkg 0402LF  page 152 : 1 = P12V_AUX ; 2 = P12V_SCM_OV_FB
PR4011  Q_RES  10K 1% CHIP  pkg 0402LF  page 152 : 1 = P12V_SCM_OV_FB ; 2 = GND
PR4012  Q_RES  0 5% CHIP  pkg 0402LF  page 152 : 1 = P12V_SCM_PWRGD ; 2 = HP_LVC3_SCM_HSC_PWRGD
PR4014  Q_RES  49.9 1% CHIP  pkg 0603LF  page 152 : 1 = P12V_AUX ; 2 = P12V_SCM_AVIN_PD
PR4522  Q_RES  10M 1% CHIP  pkg 0402LF  page 140 : 1 = P12V_OCP_V3_2 ; 2 = P12V_OCP_GATE_2
PR4523  Q_RES  10M 1% CHIP  pkg 0402LF  page 140 : 1 = P3V3_OCP_V3_2_R ; 2 = P3V3_OCP_GATE_2
PR4524  Q_RES  10M 1% CHIP  pkg 0402LF  page 134 : 1 = P12V_OCP_SFF ; 2 = P12V_OCP_GATE_1
PR4525  Q_RES  10M 1% CHIP  pkg 0402LF  page 134 : 1 = P3V3_OCP_SFF_R ; 2 = P3V3_OCP_GATE_PU202_1
PR4526  Q_RES  10M 1% CHIP  pkg 0402LF  page 152 : 1 = P12V_SCM_R ; 2 = P12V_SCM_GATE
PR4527  Q_RES  10M 1% CHIP  pkg 0402LF  page 146 : 1 = P3V3_E1S_0_R ; 2 = P3V3_E1S_GATE_0
PR4528  Q_RES  10M 1% CHIP  pkg 0402LF  page 146 : 1 = P12V_E1S_0 ; 2 = P12V_E1S_GATE_0
PR4540  Q_RES  20K 1% CHIP  pkg 0402LF  page 152 : 1 = P12V_SCM_ISET ; 2 = P12V_SCM_ISET_R
PR4541  Q_RES  20K 1% CHIP  pkg 0402LF  page 147 : 1 = P12V_E1S_ISET_0 ; 2 = P12V_E1S_ISET_0_R
PR5481  Q_RES  4.53K 1% CHIP  pkg 0402LF  page 134 : 1 = P3V3_OCP_SENSE_1 ; 2 = GND
PR5484  Q_RES  30.1K 1% CHIP  pkg 0402LF  page 134 : 1 = P12V_OCP_CB_1 ; 2 = GND
PR6000  Q_RES  0 5% CHIP  pkg 0402LF  page 192 : 1 = GND ; 2 = PVDD_33_S5_MODE

PR6001  Q_SP_RES4P  0.0003 1% CHIP  pkg R2725_4P  page 266
  1A  \1a\  BI  = P12V_PSU
  1B  \1b\  BI  = P12V_HSC_SENSE2_R1_P
  2A  \2a\  BI  = P12V_MAIN_R
  2B  \2b\  BI  = P12V_HSC_SENSE2_R1_N

PR6002  Q_SP_RES4P  0.003 1% CHIP  pkg R2512_4PXM  page 266
  1A  \1a\  BI  = P12V_PSU
  1B  \1b\  BI  = P12V_HSC_SENSE1_P
  2A  \2a\  BI  = P12V_MAIN_R_0
  2B  \2b\  BI  = P12V_HSC_SENSE1_N

PR6003  Q_RES  10K 1% CHIP  pkg 0402LF  page 269 : 1 = P1V8_AUX_CS ; 2 = GND
PR6004  Q_RES  11.5K 1% CHIP  pkg 0402LF  page 270 : 1 = P1V2_AUX_CS ; 2 = GND
PR6005  Q_RES  60.4K 1% CHIP  pkg 0402LF  page 270 : 1 = GND ; 2 = P1V2_AUX_MODE
PR6006  Q_RES  60.4K 1% CHIP  pkg 0402LF  page 269 : 1 = GND ; 2 = P1V8_AUX_MODE
PR6007  Q_RES  20K 1% CHIP  pkg 0402LF  page 269 : 1 = P1V8_AUX_FB ; 2 = P1V8_AUX
PR6008  Q_RES  10K 1% CHIP  pkg 0402LF  page 270 : 1 = P1V2_AUX_FB ; 2 = P1V2_AUX
PR6010  Q_RES  10K 1% CHIP  pkg 0402LF  page 269 : 1 = P1V8_AUX_FB ; 2 = GND
PR6011  Q_RES  10K 1% CHIP  pkg 0402LF  page 270 : 1 = P1V2_AUX_FB ; 2 = GND
PR6500  Q_RES  0 5% CHIP  pkg 0402LF  page 360 : 1 = GND ; 2 = P1V8_RETIMER_CPU0_MODE
PR6501  Q_RES  0 5% CHIP  pkg 0402LF  page 360 : 1 = P3V3_AUX ; 2 = P1V8_RETIMER_CPU0_VCC
PR6502  Q_RES  7.15K 1% CHIP  pkg 0402LF  page 360 : 1 = P1V8_RETIMER_CPU0_CS ; 2 = GND
PR6505  Q_RES  20K 1% CHIP  pkg 0402LF  page 360 : 1 = P1V8_RETIMER_CPU0_FB ; 2 = P1V8_CPU0_RT_1D
PR6507  Q_RES  10K 1% CHIP  pkg 0402LF  page 360 : 1 = P1V8_RETIMER_CPU0_FB ; 2 = GND
PR6520  Q_RES  0 5% CHIP  pkg 0402LF  page 361 : 1 = GND ; 2 = P1V8_RETIMER_CPU1_MODE
PR6521  Q_RES  0 5% CHIP  pkg 0402LF  page 361 : 1 = P3V3_AUX ; 2 = P1V8_RETIMER_CPU1_VCC
PR6522  Q_RES  7.15K 1% CHIP  pkg 0402LF  page 361 : 1 = P1V8_RETIMER_CPU1_CS ; 2 = GND
PR6524  Q_RES  20K 1% CHIP  pkg 0402LF  page 361 : 1 = P1V8_RETIMER_CPU1_FB ; 2 = P1V8_CPU1_RT_1D
PR6526  Q_RES  10K 1% CHIP  pkg 0402LF  page 361 : 1 = P1V8_RETIMER_CPU1_FB ; 2 = GND
PR6530  Q_RES  49.9 1% CHIP  pkg 0402LF  page 362 : 1 = P0V9_RETIMER_CPU0_SENSE_SH_P ; 2 = P0V9_CPU0_RT_2D
PR6531  Q_RES  0 5% CHIP  pkg 0402LF  page 362 : 1 = P0V9_RETIMER_CPU0_SENSE_SH_P ; 2 = P0V9_RETIMER_CPU0_SENSE_R_P
PR6532  Q_RES  49.9 1% CHIP  pkg 0402LF  page 362 : 1 = P0V9_RETIMER_CPU0_SENSE_SH_N ; 2 = GND
PR6533  Q_RES  22.1K 1% CHIP  pkg 0402LF  page 364 : 1 = GND ; 2 = P0V9_RETIMER_CPU1_ADDR
PR6538  Q_RES  1 1% CHIP  pkg 0402LF  page 364 : 1 = P0V9_RETIMER_CPU1_VCC ; 2 = P3V3_AUX
PR6539  Q_RES  0 5% CHIP  pkg 0402LF  page 364 : 1 = NC_P0V9_RETIMER_CPU1_IMON3 ; 2 = GND
PR6540  Q_RES  0 5% CHIP  pkg 0402LF  page 364 : 1 = NC_P0V9_RETIMER_CPU1_IMON4 ; 2 = GND
PR6541  Q_RES  0 5% CHIP  pkg 0402LF  page 364 : 1 = NC_P0V9_RETIMER_CPU1_IMON5 ; 2 = GND
PR6542  Q_RES  0 5% CHIP  pkg 0402LF  page 364 : 1 = NC_P0V9_RETIMER_CPU1_IMON6 ; 2 = GND
PR6543  Q_RES  0 5% CHIP  pkg 0402LF  page 364 : 1 = NC_P0V9_RETIMER_CPU1_IMON7 ; 2 = GND
PR6544  Q_RES  0 5% CHIP  pkg 0402LF  page 364 : 1 = NC_P0V9_RETIMER_CPU1_IMON8 ; 2 = GND
PR6548  Q_RES  0 5% CHIP  pkg 0402LF  page 364 : 1 = P0V9_RETIMER_CPU1_TEMP1_R ; 2 = GND
PR6550  Q_RES  0 5% CHIP  pkg 0402LF  page 363 : 1 = P5V_AUX ; 2 = P0V9_RETIMER_CPU0_PVCC
PR6551  Q_RES  0 5% EMPTY  pkg 0402LF  page 363 : 1 = P3V3_AUX ; 2 = P0V9_RETIMER_CPU0_PVCC
PR6552  Q_RES  2.2 5% CHIP  pkg 0402LF  page 363 : 1 = P0V9_RETIMER_CPU0_PVCC ; 2 = P0V9_RETIMER_CPU0_VCC1
PR6553  Q_RES  8.87K 1% EMPTY  pkg 0402LF  page 363 : 1 = P0V9_RETIMER_CPU0_LSET1 ; 2 = GND
PR6554  Q_RES  5.6 1% CHIP  pkg 0402LF  page 363 : 1 = SW_P0V9_RETIMER_CPU0_BOOT1 ; 2 = SW_P0V9_RETIMER_CPU0_BOOT1_RC
PR6555  Q_RES  1.5 1% EMPTY  pkg 0402LF  page 363 : 1 = SW_P0V9_RETIMER_CPU0_SW1_RC ; 2 = GND
PR6556  Q_RES  0 5% CHIP  pkg 0402LF  page 363 : 1 = P0V9_RETIMER_CPU0_VOS1 ; 2 = P0V9_CPU0_RT_2D
PR6557  Q_RES  499 1% CHIP  pkg 0603LF  page 363 : 1 = P0V9_CPU0_RT_2D ; 2 = GND
PR6560  Q_RES  2.2 5% CHIP  pkg 0402LF  page 363 : 1 = P0V9_RETIMER_CPU0_PVCC ; 2 = P0V9_RETIMER_CPU0_VCC2
PR6561  Q_RES  8.87K 1% EMPTY  pkg 0402LF  page 363 : 1 = P0V9_RETIMER_CPU0_LSET2 ; 2 = GND
PR6562  Q_RES  5.6 1% CHIP  pkg 0402LF  page 363 : 1 = SW_P0V9_RETIMER_CPU0_BOOT2 ; 2 = SW_P0V9_RETIMER_CPU0_BOOT2_RC
PR6563  Q_RES  1.5 1% EMPTY  pkg 0402LF  page 363 : 1 = SW_P0V9_RETIMER_CPU0_SW2_RC ; 2 = GND
PR6564  Q_RES  0 5% CHIP  pkg 0402LF  page 363 : 1 = P0V9_RETIMER_CPU0_VOS2 ; 2 = P0V9_CPU0_RT_2D
PR6600  Q_RES  49.9 1% CHIP  pkg 0402LF  page 364 : 1 = P0V9_RETIMER_CPU1_SENSE_SH_P ; 2 = P0V9_CPU1_RT_2D
PR6601  Q_RES  0 5% CHIP  pkg 0402LF  page 364 : 1 = P0V9_RETIMER_CPU1_SENSE_SH_P ; 2 = P0V9_RETIMER_CPU1_SENSE_R_P
PR6602  Q_RES  49.9 1% CHIP  pkg 0402LF  page 364 : 1 = P0V9_RETIMER_CPU1_SENSE_SH_N ; 2 = GND
PR6603  Q_RES  0 5% CHIP  pkg 0402LF  page 362 : 1 = GND ; 2 = P0V9_RETIMER_CPU0_ADDR
PR6604  Q_RES  5.36K 1% EMPTY  pkg 0402LF  page 362 : 1 = P5V_AUX ; 2 = P0V9_RETIMER_CPU0_VMON
PR6605  Q_RES  0 5% CHIP  pkg 0402LF  page 362 : 1 = P0V9_RETIMER_CPU0_VMON ; 2 = GND
PR6606  Q_RES  0 5% CHIP  pkg 0402LF  page 362 : 1 = P12V_AUX ; 2 = P0V9_RETIMER_CPU0_VINSEN
PR6607  Q_RES  1K 1% EMPTY  pkg 0402LF  page 362 : 1 = P0V9_RETIMER_CPU0_VINSEN ; 2 = GND
PR6608  Q_RES  1 1% CHIP  pkg 0402LF  page 362 : 1 = P0V9_RETIMER_CPU0_VCC ; 2 = P3V3_AUX
PR6609  Q_RES  0 5% CHIP  pkg 0402LF  page 362 : 1 = NC_P0V9_RETIMER_CPU0_IMON3 ; 2 = GND
PR6610  Q_RES  0 5% CHIP  pkg 0402LF  page 362 : 1 = NC_P0V9_RETIMER_CPU0_IMON4 ; 2 = GND
PR6611  Q_RES  0 5% CHIP  pkg 0402LF  page 362 : 1 = NC_P0V9_RETIMER_CPU0_IMON5 ; 2 = GND
PR6612  Q_RES  0 5% CHIP  pkg 0402LF  page 362 : 1 = NC_P0V9_RETIMER_CPU0_IMON6 ; 2 = GND
PR6613  Q_RES  0 5% CHIP  pkg 0402LF  page 362 : 1 = NC_P0V9_RETIMER_CPU0_IMON7 ; 2 = GND
PR6614  Q_RES  0 5% CHIP  pkg 0402LF  page 362 : 1 = NC_P0V9_RETIMER_CPU0_IMON8 ; 2 = GND
PR6615  Q_RES  1K 1% CHIP  pkg 0402LF  page 362 : 1 = P3V3_AUX ; 2 = TP_P0V9_RETIMER_CPU0_VRHOT
PR6616  Q_RES  0 5% CHIP  pkg 0402LF  page 362 : 1 = P0V9_RETIMER_CPU0_VRHOT ; 2 = TP_P0V9_RETIMER_CPU0_VRHOT
PR6618  Q_RES  0 5% CHIP  pkg 0402LF  page 362 : 1 = P0V9_RETIMER_CPU0_TEMP1_R ; 2 = GND
PR6619  Q_RES  0 5% CHIP  pkg 0402LF  page 365 : 1 = P5V_AUX ; 2 = P0V9_RETIMER_CPU1_PVCC
PR6620  Q_RES  0 5% EMPTY  pkg 0402LF  page 365 : 1 = P3V3_AUX ; 2 = P0V9_RETIMER_CPU1_PVCC
PR6621  Q_RES  2.2 5% CHIP  pkg 0402LF  page 365 : 1 = P0V9_RETIMER_CPU1_PVCC ; 2 = P0V9_RETIMER_CPU1_VCC1
PR6622  Q_RES  8.87K 1% EMPTY  pkg 0402LF  page 365 : 1 = P0V9_RETIMER_CPU1_LSET1 ; 2 = GND
PR6623  Q_RES  5.6 1% CHIP  pkg 0402LF  page 365 : 1 = SW_P0V9_RETIMER_CPU1_BOOT1 ; 2 = SW_P0V9_RETIMER_CPU1_BOOT1_RC
PR6624  Q_RES  1.5 1% EMPTY  pkg 0402LF  page 365 : 1 = SW_P0V9_RETIMER_CPU1_SW1_RC ; 2 = GND
